FILE_TYPE = CONNECTIVITY;
{Allegro Design Entry HDL 16.6-p007 (v16-6-112F) 10/10/2012}
"PAGE_NUMBER" = 40;
0"NC";
1"GND\g";
2"GND\g";
3"GND\g";
4"GND\g";
5"GND\g";
6"GND\g";
7"GND\g";
8"GND\g";
%"GND"
"1","(-2625,450)","0","mstr_symbols","I11";
;
VOLTAGE"0.0V"
SIZE"1B"
CDS_LIB"mstr_symbols"
BODY_TYPE"PLUMBING"
HDL_POWER"GND";
"A\NAC"1;
%"GND"
"1","(-775,450)","0","mstr_symbols","I13";
;
VOLTAGE"0.0V"
CDS_LIB"mstr_symbols"
SIZE"1B"
BODY_TYPE"PLUMBING"
HDL_POWER"GND";
"A\NAC"2;
%"GND"
"1","(-2325,475)","0","mstr_symbols","I14";
;
VOLTAGE"0.0V"
CDS_LIB"mstr_symbols"
SIZE"1B"
BODY_TYPE"PLUMBING"
HDL_POWER"GND";
"A\NAC"3;
%"SKX_EXT_B"
"23","(-7050,2575)","0","chpset_lib","I20";
;
CDS_SEC"23"
LOCATION"U5D1"
PART_NUMBER"TBD"
MATERIAL"IC"
PACK_TYPE"BGA1"
SEC_TYPE"BGA1"
CDS_LIB"chpset_lib"
SEC"23"
CDS_LOCATION"U5D1"
ROOM"CPU0";
"VSS<1094>"
$PN"J74"6;
"VSS<1095>"
$PN"J72"6;
"VSS<1096>"
$PN"J40"6;
"VSS<1097>"
$PN"J38"6;
"VSS<1098>"
$PN"J34"6;
"VSS<1099>"
$PN"J32"6;
"VSS<1100>"
$PN"J28"6;
"VSS<1101>"
$PN"J26"6;
"VSS<1102>"
$PN"J22"6;
"VSS<1103>"
$PN"J14"6;
"VSS<1104>"
$PN"J12"6;
"VSS<1105>"
$PN"J4"6;
"VSS<1106>"
$PN"DN44"6;
"VSS<1107>"
$PN"H75"6;
"VSS<1108>"
$PN"H71"6;
"VSS<1109>"
$PN"H65"6;
"VSS<1110>"
$PN"H41"6;
"VSS<1111>"
$PN"H39"6;
"VSS<1112>"
$PN"H37"6;
"VSS<1113>"
$PN"H35"6;
"VSS<1114>"
$PN"H33"6;
"VSS<1115>"
$PN"H31"6;
"VSS<1116>"
$PN"H29"6;
"VSS<1117>"
$PN"H27"6;
"VSS<1118>"
$PN"H25"6;
"VSS<1119>"
$PN"H11"6;
"VSS<1120>"
$PN"H3"6;
"VSS<1121>"
$PN"G82"6;
"VSS<1122>"
$PN"G80"6;
"VSS<1123>"
$PN"G78"6;
"VSS<1124>"
$PN"G76"6;
"VSS<1125>"
$PN"G70"6;
"VSS<1126>"
$PN"G66"6;
"VSS<1127>"
$PN"G42"6;
"VSS<1128>"
$PN"G38"6;
"VSS<1129>"
$PN"G36"6;
"VSS<1130>"
$PN"G32"6;
"VSS<1131>"
$PN"G30"6;
"VSS<1132>"
$PN"G26"6;
"VSS<1133>"
$PN"G24"6;
"VSS<1134>"
$PN"G22"6;
"VSS<1135>"
$PN"G8"6;
"VSS<1136>"
$PN"G4"6;
"VSS<1137>"
$PN"F69"6;
"VSS<1138>"
$PN"F67"6;
"VSS<1139>"
$PN"F43"6;
"VSS<1140>"
$PN"F37"6;
"VSS<1141>"
$PN"F31"6;
"VSS<1142>"
$PN"F25"6;
"VSS<1143>"
$PN"F19"6;
"VSS<1144>"
$PN"F17"6;
"VSS<1145>"
$PN"F5"6;
"VSS<1146>"
$PN"E76"6;
"VSS<1147>"
$PN"E74"6;
"VSS<1148>"
$PN"E72"6;
"VSS<1149>"
$PN"E22"6;
"VSS<1150>"
$PN"E20"6;
"VSS<1151>"
$PN"E18"6;
"VSS<1152>"
$PN"E16"6;
"VSS<1153>"
$PN"E8"6;
"VSS<1154>"
$PN"E6"6;
"VSS<1155>"
$PN"D77"6;
"VSS<1156>"
$PN"D43"6;
"VSS<1157>"
$PN"D41"6;
"VSS<1158>"
$PN"D39"6;
"VSS<1159>"
$PN"D37"6;
"VSS<1160>"
$PN"D35"6;
"VSS<1161>"
$PN"D33"6;
"VSS<1162>"
$PN"D31"6;
"VSS<1163>"
$PN"D29"6;
"VSS<1164>"
$PN"D27"6;
"VSS<1165>"
$PN"D25"6;
"VSS<1166>"
$PN"D13"6;
"VSS<1167>"
$PN"D11"6;
"VSS<1168>"
$PN"CM27"6;
"VSS<1169>"
$PN"C78"6;
"VSS<1170>"
$PN"C76"6;
"VSS<1171>"
$PN"C16"6;
"VSS<1172>"
$PN"C14"6;
"VSS<1173>"
$PN"C12"6;
"VSS<1174>"
$PN"C10"4;
"VSS<1175>"
$PN"C8"4;
"VSS<1176>"
$PN"B75"4;
"VSS<1177>"
$PN"B71"4;
"VSS<1178>"
$PN"B37"4;
"VSS<1179>"
$PN"B31"4;
"VSS<1180>"
$PN"B25"4;
"VSS<1181>"
$PN"A38"4;
"VSS<1182>"
$PN"A36"4;
"VSS<1183>"
$PN"A32"4;
"VSS<1184>"
$PN"A30"4;
"VSS<1185>"
$PN"A26"4;
"VSS<1186>"
$PN"AC58"4;
"VSS<1187>"
$PN"AC60"4;
"VSS<1188>"
$PN"AC62"4;
"VSS<1189>"
$PN"AJ4"4;
"VSS<1190>"
$PN"AR6"4;
"VSS<1191>"
$PN"CG6"4;
"VSS<1192>"
$PN"CW6"4;
"VSS<1193>"
$PN"DE48"4;
"VSS<1194>"
$PN"DE50"4;
"VSS<1195>"
$PN"DE52"4;
"VSS<1196>"
$PN"DE54"4;
"VSS<1197>"
$PN"DE56"4;
"VSS<1198>"
$PN"DE58"4;
"VSS<1199>"
$PN"DE60"4;
"VSS<1200>"
$PN"DE62"4;
"VSS<1201>"
$PN"DL8"4;
"VSS<1202>"
$PN"DN18"4;
"VSS<1203>"
$PN"DP45"4;
"VSS<1204>"
$PN"DP47"4;
"VSS<1205>"
$PN"DP49"4;
"VSS<1206>"
$PN"DP51"4;
"VSS<1207>"
$PN"DP53"4;
"VSS<1208>"
$PN"DP55"4;
"VSS<1209>"
$PN"DP57"4;
"VSS<1210>"
$PN"DP59"4;
"VSS<1211>"
$PN"DP61"4;
"VSS<1212>"
$PN"DP63"4;
"VSS<1213>"
$PN"DP9"4;
"VSS<1214>"
$PN"DV19"4;
"VSS<1215>"
$PN"DY45"4;
"VSS<1216>"
$PN"DY47"4;
"VSS<1217>"
$PN"DY49"4;
"VSS<1218>"
$PN"DY51"4;
"VSS<1219>"
$PN"DY53"4;
"VSS<1220>"
$PN"DY55"4;
"VSS<1221>"
$PN"DY57"4;
"VSS<1222>"
$PN"DY59"4;
"VSS<1223>"
$PN"DY61"4;
"VSS<1224>"
$PN"DY63"4;
"VSS<1225>"
$PN"EA14"4;
"VSS<1226>"
$PN"L8"4;
"VSS<1227>"
$PN"V11"4;
"VSS<1228>"
$PN"E66"4;
"VSS<1229>"
$PN"ED69"4;
"VSS<1230>"
$PN"EE80"4;
"VSS<1231>"
$PN"EE8"4;
"VSS<1232>"
$PN"EE40"4;
"VSS<1233>"
$PN"ED81"4;
"VSS<1234>"
$PN"ED7"4;
"VSS<1235>"
$PN"ED41"4;
"VSS<1236>"
$PN"EC82"4;
"VSS<1237>"
$PN"EC6"4;
"VSS<1238>"
$PN"EC42"4;
"VSS<1239>"
$PN"DW2"4;
"VSS<1240>"
$PN"EB83"4;
"VSS<1241>"
$PN"EA84"4;
"VSS<1242>"
$PN"DY85"4;
"VSS<1243>"
$PN"J86"4;
"VSS<1244>"
$PN"E82"4;
"VSS<1245>"
$PN"D81"4;
"VSS<1246>"
$PN"D3"4;
"VSS<1247>"
$PN"C80"4;
"VSS<1248>"
$PN"C4"4;
"VSS<1249>"
$PN"B79"4;
"VSS<1250>"
$PN"B5"4;
"VSS<1251>"
$PN"B43"4;
"VSS<1252>"
$PN"A42"4;
"VSS<1253>"
$PN"B9"4;
%"SKX_EXT_B"
"24","(-5225,2575)","0","chpset_lib","I21";
;
CDS_SEC"24"
LOCATION"U5D1"
PART_NUMBER"TBD"
MATERIAL"IC"
PACK_TYPE"BGA1"
SEC_TYPE"BGA1"
CDS_LIB"chpset_lib"
SEC"24"
CDS_LOCATION"U5D1"
ROOM"CPU0";
"VSS<934>"
$PN"AA16"7;
"VSS<935>"
$PN"AA4"7;
"VSS<936>"
$PN"Y85"7;
"VSS<937>"
$PN"Y83"7;
"VSS<938>"
$PN"Y81"7;
"VSS<939>"
$PN"Y79"7;
"VSS<940>"
$PN"Y73"7;
"VSS<941>"
$PN"Y71"7;
"VSS<942>"
$PN"Y9"7;
"VSS<943>"
$PN"Y7"7;
"VSS<944>"
$PN"Y67"7;
"VSS<945>"
$PN"Y5"7;
"VSS<946>"
$PN"Y17"7;
"VSS<947>"
$PN"Y15"7;
"VSS<948>"
$PN"W82"7;
"VSS<949>"
$PN"W78"7;
"VSS<950>"
$PN"W74"7;
"VSS<951>"
$PN"W68"7;
"VSS<952>"
$PN"W42"7;
"VSS<953>"
$PN"W40"7;
"VSS<954>"
$PN"W38"7;
"VSS<955>"
$PN"W36"7;
"VSS<956>"
$PN"W34"7;
"VSS<957>"
$PN"W32"7;
"VSS<958>"
$PN"W30"7;
"VSS<959>"
$PN"W28"7;
"VSS<960>"
$PN"W26"7;
"VSS<961>"
$PN"W24"7;
"VSS<962>"
$PN"W22"7;
"VSS<963>"
$PN"W12"7;
"VSS<964>"
$PN"AC56"7;
"VSS<965>"
$PN"W8"7;
"VSS<966>"
$PN"V83"7;
"VSS<967>"
$PN"V77"7;
"VSS<968>"
$PN"V75"7;
"VSS<969>"
$PN"V73"7;
"VSS<970>"
$PN"V43"7;
"VSS<971>"
$PN"V23"7;
"VSS<972>"
$PN"V21"7;
"VSS<973>"
$PN"V15"7;
"VSS<974>"
$PN"V13"7;
"VSS<975>"
$PN"V9"7;
"VSS<976>"
$PN"V5"7;
"VSS<977>"
$PN"V1"7;
"VSS<978>"
$PN"U86"7;
"VSS<979>"
$PN"U80"7;
"VSS<980>"
$PN"U78"7;
"VSS<981>"
$PN"U76"7;
"VSS<982>"
$PN"U74"7;
"VSS<983>"
$PN"U70"7;
"VSS<984>"
$PN"U68"7;
"VSS<985>"
$PN"U42"7;
"VSS<986>"
$PN"U36"7;
"VSS<987>"
$PN"U30"7;
"VSS<988>"
$PN"U24"7;
"VSS<989>"
$PN"U22"7;
"VSS<990>"
$PN"U20"7;
"VSS<991>"
$PN"U6"7;
"VSS<992>"
$PN"U4"7;
"VSS<993>"
$PN"U2"7;
"VSS<994>"
$PN"T85"7;
"VSS<995>"
$PN"T83"7;
"VSS<996>"
$PN"T77"7;
"VSS<997>"
$PN"T73"7;
"VSS<998>"
$PN"T65"7;
"VSS<999>"
$PN"T41"7;
"VSS<1000>"
$PN"T37"7;
"VSS<1001>"
$PN"T35"7;
"VSS<1002>"
$PN"T31"7;
"VSS<1003>"
$PN"T29"7;
"VSS<1004>"
$PN"T25"7;
"VSS<1005>"
$PN"T17"7;
"VSS<1006>"
$PN"T13"7;
"VSS<1007>"
$PN"R86"7;
"VSS<1008>"
$PN"R78"7;
"VSS<1009>"
$PN"R72"7;
"VSS<1010>"
$PN"R68"7;
"VSS<1011>"
$PN"R40"7;
"VSS<1012>"
$PN"R38"7;
"VSS<1013>"
$PN"R34"7;
"VSS<1014>"
$PN"R32"5;
"VSS<1015>"
$PN"R28"5;
"VSS<1016>"
$PN"R26"5;
"VSS<1017>"
$PN"R22"5;
"VSS<1018>"
$PN"R4"5;
"VSS<1019>"
$PN"R2"5;
"VSS<1020>"
$PN"R18"5;
"VSS<1021>"
$PN"R14"5;
"VSS<1022>"
$PN"P83"5;
"VSS<1023>"
$PN"P81"5;
"VSS<1024>"
$PN"P71"5;
"VSS<1025>"
$PN"P69"5;
"VSS<1026>"
$PN"P67"5;
"VSS<1027>"
$PN"P39"5;
"VSS<1028>"
$PN"P33"5;
"VSS<1029>"
$PN"P27"5;
"VSS<1030>"
$PN"P15"5;
"VSS<1031>"
$PN"P11"5;
"VSS<1032>"
$PN"N8"5;
"VSS<1033>"
$PN"N4"5;
"VSS<1034>"
$PN"N78"5;
"VSS<1035>"
$PN"N76"5;
"VSS<1036>"
$PN"N74"5;
"VSS<1037>"
$PN"N72"5;
"VSS<1038>"
$PN"N70"5;
"VSS<1039>"
$PN"N66"5;
"VSS<1040>"
$PN"N6"5;
"VSS<1041>"
$PN"N22"5;
"VSS<1042>"
$PN"N20"5;
"VSS<1043>"
$PN"DM19"5;
"VSS<1044>"
$PN"M85"5;
"VSS<1045>"
$PN"M83"5;
"VSS<1046>"
$PN"M79"5;
"VSS<1047>"
$PN"M71"5;
"VSS<1048>"
$PN"M65"5;
"VSS<1049>"
$PN"M43"5;
"VSS<1050>"
$PN"M41"5;
"VSS<1051>"
$PN"M39"5;
"VSS<1052>"
$PN"M37"5;
"VSS<1053>"
$PN"M35"5;
"VSS<1054>"
$PN"M33"5;
"VSS<1055>"
$PN"M31"5;
"VSS<1056>"
$PN"M29"5;
"VSS<1057>"
$PN"M27"5;
"VSS<1058>"
$PN"M25"5;
"VSS<1059>"
$PN"M23"5;
"VSS<1060>"
$PN"M19"5;
"VSS<1061>"
$PN"M17"5;
"VSS<1062>"
$PN"M15"5;
"VSS<1063>"
$PN"CT7"5;
"VSS<1064>"
$PN"BT9"5;
"VSS<1065>"
$PN"L82"5;
"VSS<1066>"
$PN"L80"5;
"VSS<1067>"
$PN"L78"5;
"VSS<1068>"
$PN"L72"5;
"VSS<1069>"
$PN"L22"5;
"VSS<1070>"
$PN"L20"5;
"VSS<1071>"
$PN"L6"5;
"VSS<1072>"
$PN"L2"5;
"VSS<1073>"
$PN"L10"5;
"VSS<1074>"
$PN"K85"5;
"VSS<1075>"
$PN"K83"5;
"VSS<1076>"
$PN"K81"5;
"VSS<1077>"
$PN"K77"5;
"VSS<1078>"
$PN"K73"5;
"VSS<1079>"
$PN"K71"5;
"VSS<1080>"
$PN"K69"5;
"VSS<1081>"
$PN"K67"5;
"VSS<1082>"
$PN"K65"5;
"VSS<1083>"
$PN"K39"5;
"VSS<1084>"
$PN"K33"5;
"VSS<1085>"
$PN"K27"5;
"VSS<1086>"
$PN"DB7"5;
"VSS<1087>"
$PN"K17"5;
"VSS<1088>"
$PN"K13"5;
"VSS<1089>"
$PN"K11"5;
"VSS<1090>"
$PN"K1"5;
"VSS<1091>"
$PN"J84"5;
"VSS<1092>"
$PN"J82"5;
"VSS<1093>"
$PN"J76"5;
%"SKX_EXT_B"
"25","(-3400,2575)","0","chpset_lib","I22";
;
CDS_SEC"25"
LOCATION"U5D1"
PART_NUMBER"TBD"
MATERIAL"IC"
PACK_TYPE"BGA1"
SEC_TYPE"BGA1"
CDS_LIB"chpset_lib"
SEC"25"
CDS_LOCATION"U5D1"
ROOM"CPU0";
"VSS<774>"
$PN"AL68"1;
"VSS<775>"
$PN"AL64"1;
"VSS<776>"
$PN"AL56"1;
"VSS<777>"
$PN"AL32"1;
"VSS<778>"
$PN"AL30"1;
"VSS<779>"
$PN"AL24"1;
"VSS<780>"
$PN"AL10"1;
"VSS<781>"
$PN"AL4"1;
"VSS<782>"
$PN"AK85"1;
"VSS<783>"
$PN"AK83"1;
"VSS<784>"
$PN"AK81"1;
"VSS<785>"
$PN"AK79"1;
"VSS<786>"
$PN"AK73"1;
"VSS<787>"
$PN"AK67"1;
"VSS<788>"
$PN"AK65"1;
"VSS<789>"
$PN"AK55"1;
"VSS<790>"
$PN"AK33"1;
"VSS<791>"
$PN"AK31"1;
"VSS<792>"
$PN"AK29"1;
"VSS<793>"
$PN"AK25"1;
"VSS<794>"
$PN"AK23"1;
"VSS<795>"
$PN"AK19"1;
"VSS<796>"
$PN"AK13"1;
"VSS<797>"
$PN"AK9"1;
"VSS<798>"
$PN"AJ86"1;
"VSS<799>"
$PN"AJ82"1;
"VSS<800>"
$PN"AJ78"1;
"VSS<801>"
$PN"AJ74"1;
"VSS<802>"
$PN"AJ68"1;
"VSS<803>"
$PN"AJ66"1;
"VSS<804>"
$PN"AJ54"1;
"VSS<805>"
$PN"AJ52"1;
"VSS<806>"
$PN"AJ50"1;
"VSS<807>"
$PN"AJ48"1;
"VSS<808>"
$PN"AJ46"1;
"VSS<809>"
$PN"AJ34"1;
"VSS<810>"
$PN"AJ32"1;
"VSS<811>"
$PN"AJ28"1;
"VSS<812>"
$PN"AJ26"1;
"VSS<813>"
$PN"AJ22"1;
"VSS<814>"
$PN"AJ8"1;
"VSS<815>"
$PN"AH83"1;
"VSS<816>"
$PN"AH77"1;
"VSS<817>"
$PN"AH75"1;
"VSS<818>"
$PN"AH69"1;
"VSS<819>"
$PN"AH65"1;
"VSS<820>"
$PN"AH61"1;
"VSS<821>"
$PN"AH59"1;
"VSS<822>"
$PN"AH53"1;
"VSS<823>"
$PN"AH51"1;
"VSS<824>"
$PN"AH49"1;
"VSS<825>"
$PN"AH47"1;
"VSS<826>"
$PN"AH45"1;
"VSS<827>"
$PN"AH35"1;
"VSS<828>"
$PN"AH33"1;
"VSS<829>"
$PN"AH27"1;
"VSS<830>"
$PN"AH21"1;
"VSS<831>"
$PN"AH5"1;
"VSS<832>"
$PN"AH1"1;
"VSS<833>"
$PN"AG80"1;
"VSS<834>"
$PN"AG78"1;
"VSS<835>"
$PN"AG76"1;
"VSS<836>"
$PN"AG74"1;
"VSS<837>"
$PN"AG70"1;
"VSS<838>"
$PN"AG64"1;
"VSS<839>"
$PN"AG36"1;
"VSS<840>"
$PN"AG18"1;
"VSS<841>"
$PN"AG14"1;
"VSS<842>"
$PN"AG12"1;
"VSS<843>"
$PN"AF85"1;
"VSS<844>"
$PN"AF83"1;
"VSS<845>"
$PN"AF77"1;
"VSS<846>"
$PN"AF73"1;
"VSS<847>"
$PN"AF41"1;
"VSS<848>"
$PN"AF39"1;
"VSS<849>"
$PN"AF37"1;
"VSS<850>"
$PN"AF33"1;
"VSS<851>"
$PN"AF31"1;
"VSS<852>"
$PN"AF29"1;
"VSS<853>"
$PN"AF27"1;
"VSS<854>"
$PN"AF25"8;
"VSS<855>"
$PN"AF23"8;
"VSS<856>"
$PN"AF21"8;
"VSS<857>"
$PN"AF9"8;
"VSS<858>"
$PN"AC52"8;
"VSS<859>"
$PN"AF1"8;
"VSS<860>"
$PN"AE78"8;
"VSS<861>"
$PN"AE70"8;
"VSS<862>"
$PN"AE68"8;
"VSS<863>"
$PN"AE66"8;
"VSS<864>"
$PN"AE64"8;
"VSS<865>"
$PN"AE42"8;
"VSS<866>"
$PN"AE40"8;
"VSS<867>"
$PN"AE38"8;
"VSS<868>"
$PN"AE16"8;
"VSS<869>"
$PN"AC54"8;
"VSS<870>"
$PN"AE8"8;
"VSS<871>"
$PN"AE4"8;
"VSS<872>"
$PN"AD85"8;
"VSS<873>"
$PN"AD83"8;
"VSS<874>"
$PN"AD81"8;
"VSS<875>"
$PN"AD75"8;
"VSS<876>"
$PN"AD73"8;
"VSS<877>"
$PN"AD71"8;
"VSS<878>"
$PN"AD43"8;
"VSS<879>"
$PN"AD39"8;
"VSS<880>"
$PN"AD33"8;
"VSS<881>"
$PN"AD27"8;
"VSS<882>"
$PN"AD21"8;
"VSS<883>"
$PN"AD19"8;
"VSS<884>"
$PN"AD15"8;
"VSS<885>"
$PN"AD13"8;
"VSS<886>"
$PN"AD11"8;
"VSS<887>"
$PN"AD9"8;
"VSS<888>"
$PN"AD7"8;
"VSS<889>"
$PN"AD3"8;
"VSS<890>"
$PN"AC86"8;
"VSS<891>"
$PN"AC84"8;
"VSS<892>"
$PN"AC78"8;
"VSS<893>"
$PN"AC72"8;
"VSS<894>"
$PN"AC70"8;
"VSS<895>"
$PN"AC64"8;
"VSS<896>"
$PN"AC40"8;
"VSS<897>"
$PN"AC38"8;
"VSS<898>"
$PN"AC34"8;
"VSS<899>"
$PN"AC32"8;
"VSS<900>"
$PN"AC28"8;
"VSS<901>"
$PN"AC26"8;
"VSS<902>"
$PN"AC22"8;
"VSS<903>"
$PN"AC18"8;
"VSS<904>"
$PN"AB85"8;
"VSS<905>"
$PN"AB83"8;
"VSS<906>"
$PN"AB79"8;
"VSS<907>"
$PN"AB73"8;
"VSS<908>"
$PN"AB69"8;
"VSS<909>"
$PN"AB65"8;
"VSS<910>"
$PN"AB41"8;
"VSS<911>"
$PN"AB37"8;
"VSS<912>"
$PN"AB35"8;
"VSS<913>"
$PN"AB31"8;
"VSS<914>"
$PN"AB29"8;
"VSS<915>"
$PN"AB25"8;
"VSS<916>"
$PN"AB23"8;
"VSS<917>"
$PN"AB21"8;
"VSS<918>"
$PN"AB11"8;
"VSS<919>"
$PN"AB5"8;
"VSS<920>"
$PN"AB1"8;
"VSS<921>"
$PN"AA82"8;
"VSS<922>"
$PN"AA80"8;
"VSS<923>"
$PN"AA78"8;
"VSS<924>"
$PN"AA76"8;
"VSS<925>"
$PN"AA68"8;
"VSS<926>"
$PN"AA66"8;
"VSS<927>"
$PN"AA64"8;
"VSS<928>"
$PN"AA42"8;
"VSS<929>"
$PN"AA36"8;
"VSS<930>"
$PN"AA30"8;
"VSS<931>"
$PN"AA24"8;
"VSS<932>"
$PN"AA22"8;
"VSS<933>"
$PN"AA18"8;
%"SKX_EXT_B"
"26","(-1550,2575)","0","chpset_lib","I23";
;
CDS_SEC"26"
LOCATION"U5D1"
PART_NUMBER"TBD"
MATERIAL"IC"
PACK_TYPE"BGA1"
SEC_TYPE"BGA1"
CDS_LIB"chpset_lib"
SEC"26"
CDS_LOCATION"U5D1"
ROOM"CPU0";
"VSS<614>"
$PN"BG72"2;
"VSS<615>"
$PN"BG24"2;
"VSS<616>"
$PN"BG22"2;
"VSS<617>"
$PN"BG10"2;
"VSS<618>"
$PN"BG8"2;
"VSS<619>"
$PN"BG6"2;
"VSS<620>"
$PN"BF71"2;
"VSS<621>"
$PN"BF69"2;
"VSS<622>"
$PN"BF67"2;
"VSS<623>"
$PN"BF65"2;
"VSS<624>"
$PN"BF63"2;
"VSS<625>"
$PN"BF25"2;
"VSS<626>"
$PN"BF19"2;
"VSS<627>"
$PN"BF17"2;
"VSS<628>"
$PN"BF15"2;
"VSS<629>"
$PN"BF9"2;
"VSS<630>"
$PN"BE70"2;
"VSS<631>"
$PN"BE68"2;
"VSS<632>"
$PN"BE66"2;
"VSS<633>"
$PN"BE64"2;
"VSS<634>"
$PN"BE26"2;
"VSS<635>"
$PN"BE10"2;
"VSS<636>"
$PN"BE8"2;
"VSS<637>"
$PN"BE6"2;
"VSS<638>"
$PN"BE4"2;
"VSS<639>"
$PN"BD71"2;
"VSS<640>"
$PN"BD63"2;
"VSS<641>"
$PN"BD27"2;
"VSS<642>"
$PN"BD21"2;
"VSS<643>"
$PN"BD15"2;
"VSS<644>"
$PN"BD11"2;
"VSS<645>"
$PN"BD5"2;
"VSS<646>"
$PN"BC82"2;
"VSS<647>"
$PN"BC80"2;
"VSS<648>"
$PN"BC78"2;
"VSS<649>"
$PN"BC76"2;
"VSS<650>"
$PN"BC74"2;
"VSS<651>"
$PN"BC72"2;
"VSS<652>"
$PN"BC70"2;
"VSS<653>"
$PN"BC16"2;
"VSS<654>"
$PN"BC12"2;
"VSS<655>"
$PN"BC8"2;
"VSS<656>"
$PN"BC4"2;
"VSS<657>"
$PN"BB83"2;
"VSS<658>"
$PN"BB81"2;
"VSS<659>"
$PN"BB79"2;
"VSS<660>"
$PN"BB77"2;
"VSS<661>"
$PN"BB75"2;
"VSS<662>"
$PN"BB73"2;
"VSS<663>"
$PN"BB69"2;
"VSS<664>"
$PN"BB63"2;
"VSS<665>"
$PN"BB23"2;
"VSS<666>"
$PN"BB19"2;
"VSS<667>"
$PN"BA84"2;
"VSS<668>"
$PN"BA80"2;
"VSS<669>"
$PN"BA74"2;
"VSS<670>"
$PN"BA68"2;
"VSS<671>"
$PN"BA62"2;
"VSS<672>"
$PN"BA12"2;
"VSS<673>"
$PN"BA6"2;
"VSS<674>"
$PN"BA2"2;
"VSS<675>"
$PN"AY81"2;
"VSS<676>"
$PN"AY79"2;
"VSS<677>"
$PN"AY63"2;
"VSS<678>"
$PN"AY25"2;
"VSS<679>"
$PN"AY23"2;
"VSS<680>"
$PN"AY21"2;
"VSS<681>"
$PN"AY17"2;
"VSS<682>"
$PN"AY15"2;
"VSS<683>"
$PN"AY5"2;
"VSS<684>"
$PN"AW84"2;
"VSS<685>"
$PN"AW82"2;
"VSS<686>"
$PN"AW78"2;
"VSS<687>"
$PN"AW74"2;
"VSS<688>"
$PN"AW72"2;
"VSS<689>"
$PN"AW70"2;
"VSS<690>"
$PN"AW68"2;
"VSS<691>"
$PN"AW66"2;
"VSS<692>"
$PN"AW62"2;
"VSS<693>"
$PN"AW10"2;
"VSS<694>"
$PN"AW2"3;
"VSS<695>"
$PN"AV83"3;
"VSS<696>"
$PN"AV75"3;
"VSS<697>"
$PN"AV67"3;
"VSS<698>"
$PN"AV65"3;
"VSS<699>"
$PN"AV63"3;
"VSS<700>"
$PN"AV25"3;
"VSS<701>"
$PN"AV23"3;
"VSS<702>"
$PN"AV19"3;
"VSS<703>"
$PN"AV13"3;
"VSS<704>"
$PN"AV11"3;
"VSS<705>"
$PN"AV7"3;
"VSS<706>"
$PN"AV3"3;
"VSS<707>"
$PN"AV1"3;
"VSS<708>"
$PN"AU86"3;
"VSS<709>"
$PN"AU84"3;
"VSS<710>"
$PN"AU80"3;
"VSS<711>"
$PN"AU78"3;
"VSS<712>"
$PN"AU76"3;
"VSS<713>"
$PN"AU74"3;
"VSS<714>"
$PN"AU68"3;
"VSS<715>"
$PN"AU64"3;
"VSS<716>"
$PN"AU62"3;
"VSS<717>"
$PN"AU28"3;
"VSS<718>"
$PN"AU26"3;
"VSS<719>"
$PN"AU6"3;
"VSS<720>"
$PN"AU2"3;
"VSS<721>"
$PN"AT85"3;
"VSS<722>"
$PN"AT83"3;
"VSS<723>"
$PN"AT77"3;
"VSS<724>"
$PN"AT73"3;
"VSS<725>"
$PN"AT69"3;
"VSS<726>"
$PN"AT63"3;
"VSS<727>"
$PN"AT61"3;
"VSS<728>"
$PN"AT27"3;
"VSS<729>"
$PN"AT21"3;
"VSS<730>"
$PN"AT17"3;
"VSS<731>"
$PN"AT15"3;
"VSS<732>"
$PN"P63"3;
"VSS<733>"
$PN"AC48"3;
"VSS<734>"
$PN"AR78"3;
"VSS<735>"
$PN"AR72"3;
"VSS<736>"
$PN"AR60"3;
"VSS<737>"
$PN"AR30"3;
"VSS<738>"
$PN"AR24"3;
"VSS<739>"
$PN"AR10"3;
"VSS<740>"
$PN"AP85"3;
"VSS<741>"
$PN"AP83"3;
"VSS<742>"
$PN"AP81"3;
"VSS<743>"
$PN"AP75"3;
"VSS<744>"
$PN"AP73"3;
"VSS<745>"
$PN"AP69"3;
"VSS<746>"
$PN"AP67"3;
"VSS<747>"
$PN"AP65"3;
"VSS<748>"
$PN"AP63"3;
"VSS<749>"
$PN"AP59"3;
"VSS<750>"
$PN"AP31"3;
"VSS<751>"
$PN"AP19"3;
"VSS<752>"
$PN"AP13"3;
"VSS<753>"
$PN"AP9"3;
"VSS<754>"
$PN"AP5"3;
"VSS<755>"
$PN"AN78"3;
"VSS<756>"
$PN"AN58"3;
"VSS<757>"
$PN"AN28"3;
"VSS<758>"
$PN"AN6"3;
"VSS<759>"
$PN"AN2"3;
"VSS<760>"
$PN"AM83"3;
"VSS<761>"
$PN"AM79"3;
"VSS<762>"
$PN"AM73"3;
"VSS<763>"
$PN"AM69"3;
"VSS<764>"
$PN"AM63"3;
"VSS<765>"
$PN"AM57"3;
"VSS<766>"
$PN"AM31"3;
"VSS<767>"
$PN"AC50"3;
"VSS<768>"
$PN"AM1"3;
"VSS<769>"
$PN"AL86"3;
"VSS<770>"
$PN"AL82"3;
"VSS<771>"
$PN"AL80"3;
"VSS<772>"
$PN"AL78"3;
"VSS<773>"
$PN"AL76"3;
%"GND"
"1","(-7800,450)","0","mstr_symbols","I3";
;
VOLTAGE"0.0V"
SIZE"1B"
CDS_LIB"mstr_symbols"
BODY_TYPE"PLUMBING"
HDL_POWER"GND";
"A\NAC"4;
%"GND"
"1","(-5975,450)","0","mstr_symbols","I4";
;
VOLTAGE"0.0V"
SIZE"1B"
CDS_LIB"mstr_symbols"
BODY_TYPE"PLUMBING"
HDL_POWER"GND";
"A\NAC"5;
%"GND"
"1","(-6275,450)","0","mstr_symbols","I5";
;
VOLTAGE"0.0V"
SIZE"1B"
CDS_LIB"mstr_symbols"
BODY_TYPE"PLUMBING"
HDL_POWER"GND";
"A\NAC"6;
%"GND"
"1","(-4450,450)","0","mstr_symbols","I6";
;
VOLTAGE"0.0V"
SIZE"1B"
CDS_LIB"mstr_symbols"
BODY_TYPE"PLUMBING"
HDL_POWER"GND";
"A\NAC"7;
%"GND"
"1","(-4150,450)","0","mstr_symbols","I9";
;
VOLTAGE"0.0V"
CDS_LIB"mstr_symbols"
SIZE"1B"
BODY_TYPE"PLUMBING"
HDL_POWER"GND";
"A\NAC"8;
END.
